# TIMECARD (Time Appliance Project (Time Card)) — schematic netlist excerpt (pin names and nets, part order shuffled) for the footprints in the layout excerpt that follows; sources: Cadence DE-HDL packaged netlist, KiCad conversion of R4006-B0001-02_R01.brd

R110  RESISTOR  33OHM 1%  pkg SMC_0402R_H016  page 22 : \1\ = UART_GPS_RX_FPGA_TX ; \2\ = GPS_UART_RXD
R328  RESISTOR  4.7KOHM 1%  pkg SMC_0402R_H016  page 25 : \1\ = SG ; \2\ = FPGA_IO_7

(kicad_pcb
	(version 20260206)
	(generator "pcbnew")
	(generator_version "10.0")
	(general
		(thickness 1.6)
		(legacy_teardrops no)
	)
	(paper "A4")
	(title_block
		(title "timecard-production-celestica-r4006 — R4006-B0001-02_R01.brd")
		(comment 1 "Time Appliance Project (Time Card) / footprints 888-889 of 1113")
	)
	(layers
		(0 "F.Cu" signal "TOP")
		(4 "In1.Cu" signal "L02_GND1")
		(6 "In2.Cu" signal "L03_SIG1")
		(8 "In3.Cu" signal "L04_GND2")
		(10 "In4.Cu" signal "L05_VCC1")
		(12 "In5.Cu" signal "L06_VCC2")
		(14 "In6.Cu" signal "L07_GND3")
		(16 "In7.Cu" signal "L08_SIG2")
		(18 "In8.Cu" signal "L09_GND4")
		(2 "B.Cu" signal "BOTTOM")
		(9 "F.Adhes" user "F.Adhesive")
		(11 "B.Adhes" user "B.Adhesive")
		(13 "F.Paste" user "Package Geometry/Pastemask Top")
		(15 "B.Paste" user "Package Geometry/Pastemask Bottom")
		(5 "F.SilkS" user "Ref Des/Silkscreen Top")
		(7 "B.SilkS" user "Ref Des/Silkscreen Bottom")
		(1 "F.Mask" user "Board Geometry/Soldermask Top")
		(3 "B.Mask" user "Board Geometry/Soldermask Bottom")
		(17 "Dwgs.User" user "User.Drawings")
		(19 "Cmts.User" user "User.Comments")
		(21 "Eco1.User" user "User.Eco1")
		(23 "Eco2.User" user "User.Eco2")
		(25 "Edge.Cuts" user "Board Geometry/Outline")
		(27 "Margin" user)
		(31 "F.CrtYd" user "Package Geometry/Place Bound Top")
		(29 "B.CrtYd" user "Package Geometry/Place Bound Bottom")
		(35 "F.Fab" user "Ref Des/Assembly Top")
		(33 "B.Fab" user "Ref Des/Assembly Bottom")
	)
	(footprint ""
		(layer "B.Cu")
		(at 105.41 -64.2874 90)
		(property "Reference" "R328"
			(at 3.5306 -0.16637 270)
			(unlocked yes)
			(layer "B.SilkS")
			(effects
				(font
					(size 0.7874 0.5842)
					(thickness 0.1524)
				)
				(justify mirror)
			)
		)
		(property "Value" "VAL*"
			(at -0.02032 2.13233 90)
			(unlocked yes)
			(layer "B.Fab")
			(hide yes)
			(effects
				(font
					(size 0.7874 0.5842)
					(thickness 0.1524)
				)
				(justify mirror)
			)
		)
		(property "Tolerance" "TOL*"
			(at -0.044704 3.05435 90)
			(unlocked yes)
			(layer "Cmts.User")
			(hide yes)
			(effects
				(font
					(size 0.7874 0.5842)
					(thickness 0.1524)
				)
				(justify mirror)
			)
		)
		(property "User Part Number" "PARTNUM*"
			(at -0.02032 4.024884 90)
			(unlocked yes)
			(layer "Cmts.User")
			(hide yes)
			(effects
				(font
					(size 0.7874 0.5842)
					(thickness 0.1524)
				)
				(justify mirror)
			)
		)
		(property "Device Type" "RESISTOR-G155-14701-01,4.7KOHMA"
			(at -0.008382 1.210564 90)
			(unlocked yes)
			(layer "B.Fab")
			(hide yes)
			(effects
				(font
					(size 0.7874 0.5842)
					(thickness 0.1524)
				)
				(justify mirror)
			)
		)
		(duplicate_pad_numbers_are_jumpers no)
		(fp_line
			(start 1.143 -0.5588)
			(end 1.143 0.5588)
			(stroke
				(width 0.1)
				(type default)
			)
			(layer "B.SilkS")
		)
		(fp_line
			(start -1.143 -0.5588)
			(end 1.143 -0.5588)
			(stroke
				(width 0.1)
				(type default)
			)
			(layer "B.SilkS")
		)
		(fp_line
			(start 1.143 0.5588)
			(end -1.143 0.5588)
			(stroke
				(width 0.1)
				(type default)
			)
			(layer "B.SilkS")
		)
		(fp_line
			(start -1.143 0.5588)
			(end -1.143 -0.5588)
			(stroke
				(width 0.1)
				(type default)
			)
			(layer "B.SilkS")
		)
		(fp_poly
			(pts
				(xy 1.143 0.5588) (xy -1.143 0.5588) (xy -1.143 -0.5588) (xy 1.143 -0.5588)
			)
			(stroke
				(width 0)
				(type default)
			)
			(fill no)
			(layer "B.CrtYd")
		)
		(fp_line
			(start 0.508 -0.3048)
			(end 0.508 0.3048)
			(stroke
				(width 0.1)
				(type default)
			)
			(layer "B.Fab")
		)
		(fp_line
			(start -0.508 -0.3048)
			(end 0.508 -0.3048)
			(stroke
				(width 0.1)
				(type default)
			)
			(layer "B.Fab")
		)
		(fp_line
			(start 0.508 0.3048)
			(end -0.508 0.3048)
			(stroke
				(width 0.1)
				(type default)
			)
			(layer "B.Fab")
		)
		(fp_line
			(start -0.508 0.3048)
			(end -0.508 -0.3048)
			(stroke
				(width 0.1)
				(type default)
			)
			(layer "B.Fab")
		)
		(pad "1" smd rect
			(at 0.5334 0 270)
			(size 0.7112 0.6096)
			(layers "B.Cu" "B.Mask" "B.Paste")
			(net "SG")
		)
		(pad "2" smd rect
			(at -0.5334 0 270)
			(size 0.7112 0.6096)
			(layers "B.Cu" "B.Mask" "B.Paste")
			(net "FPGA_IO_7")
		)
		(zone
			(layer "B.Cu")
			(hatch none 0.5)
			(connect_pads
				(clearance 0)
			)
			(min_thickness 0.25)
			(keepout
				(tracks allowed)
				(vias not_allowed)
				(pads allowed)
				(copperpour not_allowed)
				(footprints allowed)
			)
			(placement
				(enabled no)
				(sheetname "")
			)
			(fill
				(thermal_gap 0.5)
				(thermal_bridge_width 0.5)
				(island_removal_mode 0)
			)
			(polygon
				(pts
					(xy 105.7148 -64.3636) (xy 105.1052 -64.3636) (xy 105.1052 -64.2112) (xy 105.7148 -64.2112)
				)
			)
		)
		(zone
			(layer "B.Cu")
			(hatch none 0.5)
			(connect_pads
				(clearance 0)
			)
			(min_thickness 0.25)
			(keepout
				(tracks not_allowed)
				(vias allowed)
				(pads allowed)
				(copperpour not_allowed)
				(footprints allowed)
			)
			(placement
				(enabled no)
				(sheetname "")
			)
			(fill
				(thermal_gap 0.5)
				(thermal_bridge_width 0.5)
				(island_removal_mode 0)
			)
			(polygon
				(pts
					(xy 105.7148 -64.3636) (xy 105.1052 -64.3636) (xy 105.1052 -64.2112) (xy 105.7148 -64.2112)
				)
			)
		)
	)
	(footprint ""
		(layer "B.Cu")
		(at 125.349 -89.535 -90)
		(property "Reference" "R110"
			(at -3.683 -0.08763 270)
			(unlocked yes)
			(layer "B.SilkS")
			(effects
				(font
					(size 0.7874 0.5842)
					(thickness 0.1524)
				)
				(justify mirror)
			)
		)
		(property "Value" "VAL*"
			(at -0.02032 2.13233 270)
			(unlocked yes)
			(layer "B.Fab")
			(hide yes)
			(effects
				(font
					(size 0.7874 0.5842)
					(thickness 0.1524)
				)
				(justify mirror)
			)
		)
		(property "Device Type" "RESISTOR-G155-133R0-01,33OHM,1%"
			(at -0.008382 1.210564 270)
			(unlocked yes)
			(layer "B.Fab")
			(hide yes)
			(effects
				(font
					(size 0.7874 0.5842)
					(thickness 0.1524)
				)
				(justify mirror)
			)
		)
		(property "User Part Number" "PARTNUM*"
			(at -0.02032 4.024884 270)
			(unlocked yes)
			(layer "Cmts.User")
			(hide yes)
			(effects
				(font
					(size 0.7874 0.5842)
					(thickness 0.1524)
				)
				(justify mirror)
			)
		)
		(property "Tolerance" "TOL*"
			(at -0.044704 3.05435 270)
			(unlocked yes)
			(layer "Cmts.User")
			(hide yes)
			(effects
				(font
					(size 0.7874 0.5842)
					(thickness 0.1524)
				)
				(justify mirror)
			)
		)
		(duplicate_pad_numbers_are_jumpers no)
		(fp_line
			(start -1.143 0.5588)
			(end -1.143 -0.5588)
			(stroke
				(width 0.1)
				(type default)
			)
			(layer "B.SilkS")
		)
		(fp_line
			(start 1.143 0.5588)
			(end -1.143 0.5588)
			(stroke
				(width 0.1)
				(type default)
			)
			(layer "B.SilkS")
		)
		(fp_line
			(start -1.143 -0.5588)
			(end 1.143 -0.5588)
			(stroke
				(width 0.1)
				(type default)
			)
			(layer "B.SilkS")
		)
		(fp_line
			(start 1.143 -0.5588)
			(end 1.143 0.5588)
			(stroke
				(width 0.1)
				(type default)
			)
			(layer "B.SilkS")
		)
		(fp_rect
			(start -1.143 -0.5588)
			(end 1.143 0.5588)
			(stroke
				(width 0)
				(type default)
			)
			(fill no)
			(layer "B.CrtYd")
		)
		(fp_line
			(start -0.508 0.3048)
			(end -0.508 -0.3048)
			(stroke
				(width 0.1)
				(type default)
			)
			(layer "B.Fab")
		)
		(fp_line
			(start 0.508 0.3048)
			(end -0.508 0.3048)
			(stroke
				(width 0.1)
				(type default)
			)
			(layer "B.Fab")
		)
		(fp_line
			(start -0.508 -0.3048)
			(end 0.508 -0.3048)
			(stroke
				(width 0.1)
				(type default)
			)
			(layer "B.Fab")
		)
		(fp_line
			(start 0.508 -0.3048)
			(end 0.508 0.3048)
			(stroke
				(width 0.1)
				(type default)
			)
			(layer "B.Fab")
		)
		(pad "1" smd rect
			(at 0.5334 0 90)
			(size 0.7112 0.6096)
			(layers "B.Cu" "B.Mask" "B.Paste")
			(net "UART_GPS_RX_FPGA_TX")
		)
		(pad "2" smd rect
			(at -0.5334 0 90)
			(size 0.7112 0.6096)
			(layers "B.Cu" "B.Mask" "B.Paste")
			(net "GPS_UART_RXD")
		)
		(zone
			(layer "B.Cu")
			(hatch none 0.5)
			(connect_pads
				(clearance 0)
			)
			(min_thickness 0.25)
			(keepout
				(tracks allowed)
				(vias not_allowed)
				(pads allowed)
				(copperpour not_allowed)
				(footprints allowed)
			)
			(placement
				(enabled no)
				(sheetname "")
			)
			(fill
				(thermal_gap 0.5)
				(thermal_bridge_width 0.5)
				(island_removal_mode 0)
			)
			(polygon
				(pts
					(xy 125.6538 -89.6112) (xy 125.0442 -89.6112) (xy 125.0442 -89.4588) (xy 125.6538 -89.4588)
				)
			)
		)
	)
)
